# Stackup_F0T_Expander_BD_18L_3p09mm_EM-890K_VL411_Rev1_20221220.xls — Vendor Stackup (pcb-stackup)
| STACKUP |  |  |  | Target Z (ohms) - MicroStrip |  |  |  |  |  |  |  | 50 |  |  | Breakout | 85 |  |  |  |  | 95 |  |  |  |  | 100 |  |  |  |  |  |  |  |  |  | Breakout |  |
|  |  |  |  | Target Z (ohms) - StripLine |  |  |  |  |  |  |  | 50 |  |  |  | 85 |  |  |  |  | 95 |  |  |  |  | 100 |  |  |  |  | 85(neck mode) |  |  |  |  |  |  |
|  |  |  |  | Z tolerance |  |  |  |  |  |  |  | 0.1 |  |  |  | +/-7.5% (for inner) ,+/-10% (for outer) |  |  |  |  | 0.1 |  |  |  |  | 0.1 |  |  |  |  | 85(neck mode) target |  |  |  |  |  |  |
|  |  |  |  | Z Type |  |  |  |  |  |  |  | Single |  |  | Single | Differential |  |  |  |  | Differential |  |  |  |  | Differential |  |  |  |  | Differential |  |  |  |  | Differential |  |
| Layer# | Material | Description |  | Copper Weight (oz) | Thickness (mil) | Tolerance (mil) | Glass Fabric | Er | Vendor Thickness (mil) | Vendor Glass Fabric | Vendor Er | Width | Vendor Width | Vendor Impedance | Width | Width | Space | Vendor Width | Vendor Space | Vendor Impedance | Width | Space | Vendor Width | Vendor Space | Vendor Impedance | Width | Space | Vendor Width | Vendor Space | Vendor Impedance | Width | Space | Vendor Width | Vendor Space | Vendor Impedance | Width | Space |
|  |  |  | Soldermask |  | 0.6 |  |  | 3.8 |  |  |  |  |  |  |  |  |  |  |  |  |  |  |  |  |  |  |  |  |  |  |  |  |  |  |  |  |  |
| 1 |  |  | TOP | 0.5+plating | 1.95 |  |  |  |  |  |  | 5.2 |  |  | 3.5 | 5.3 | 5.5 |  |  |  | 4.9 | 9.4 |  |  |  | 4.5 | 10 |  |  |  |  |  |  |  |  | 3.5 | 4.5 |
|  | EM-890K |  | PP |  | 2.7 | ±0.709 | 1078x1 | 2.92 |  |  |  |  |  |  |  |  |  |  |  |  |  |  |  |  |  |  |  |  |  |  |  |  |  |  |  |  |  |
| 2 |  |  | GND | 1 (VL411) | 1.3 |  |  |  |  |  |  |  |  |  |  |  |  |  |  |  |  |  |  |  |  |  |  |  |  |  |  |  |  |  |  |  |  |
|  | EM-890K |  | CORE |  | 4 | ±0.709 | 1078x1 | 2.93 |  |  |  |  |  |  |  |  |  |  |  |  |  |  |  |  |  |  |  |  |  |  |  |  |  |  |  |  |  |
| 3 |  |  | VCC | 1 (VL411) | 1.3 |  |  |  |  |  |  |  |  |  |  |  |  |  |  |  |  |  |  |  |  |  |  |  |  |  |  |  |  |  |  |  |  |
|  | EM-890K |  | PP |  | 8 | ±1.5 | 3313x2 | 2.97 |  |  |  |  |  |  |  |  |  |  |  |  |  |  |  |  |  |  |  |  |  |  |  |  |  |  |  |  |  |
| 4 |  |  | VCC1 | 2 (RTF) | 2.6 |  |  |  |  |  |  |  |  |  |  |  |  |  |  |  |  |  |  |  |  |  |  |  |  |  |  |  |  |  |  |  |  |
|  | EM-890K |  | CORE |  | 4 | ±0.709 | 1078x1 | 2.93 |  |  |  |  |  |  |  |  |  |  |  |  |  |  |  |  |  |  |  |  |  |  |  |  |  |  |  |  |  |
| 5 |  |  | GND1 | 1 (VL411) | 1.3 |  |  |  |  |  |  |  |  |  |  |  |  |  |  |  |  |  |  |  |  |  |  |  |  |  |  |  |  |  |  |  |  |
|  | EM-890K |  | PP |  | 8 | ±1.5 | 3313x2 | 2.97 |  |  |  |  |  |  |  |  |  |  |  |  |  |  |  |  |  |  |  |  |  |  |  |  |  |  |  |  |  |
| 6 |  |  | IN1 | 1 (VL411) | 1.3 |  |  |  |  |  |  | 6.1 |  |  | 3.5 | 6.5 | 4.6 |  |  |  | 6.3 | 9.5 |  |  |  | 5.5 | 7.5 |  |  |  | 4.5 | 3 |  |  |  | 3.5 | 4 |
|  | EM-890K |  | CORE |  | 4 | ±0.709 | 1078x1 | 2.93 |  |  |  |  |  |  |  |  |  |  |  |  |  |  |  |  |  |  |  |  |  |  |  |  |  |  |  |  |  |
| 7 |  |  | GND2 | 1 (VL411) | 1.3 |  |  |  |  |  |  |  |  |  |  |  |  |  |  |  |  |  |  |  |  |  |  |  |  |  |  |  |  |  |  |  |  |
|  | EM-890K |  | PP |  | 8 | ±1.5 | 3313x2 | 2.97 |  |  |  |  |  |  |  |  |  |  |  |  |  |  |  |  |  |  |  |  |  |  |  |  |  |  |  |  |  |
| 8 |  |  | IN2 | 1 (VL411) | 1.3 |  |  |  |  |  |  | 6.1 |  |  | 3.5 | 6.5 | 4.6 |  |  |  | 6.3 | 9.5 |  |  |  | 5.5 | 7.5 |  |  |  | 4.5 | 3 |  |  |  | 3.5 | 4 |
|  | EM-890K |  | CORE |  | 4 | ±0.709 | 1078x1 | 2.93 |  |  |  |  |  |  |  |  |  |  |  |  |  |  |  |  |  |  |  |  |  |  |  |  |  |  |  |  |  |
| 9 |  |  | GND3 | 1 (VL411) | 1.3 |  |  |  |  |  |  |  |  |  |  |  |  |  |  |  |  |  |  |  |  |  |  |  |  |  |  |  |  |  |  |  |  |
|  | EM-890K |  | PP |  | 7.8 | ±1.5 | 3313x2 | 2.97 |  |  |  |  |  |  |  |  |  |  |  |  |  |  |  |  |  |  |  |  |  |  |  |  |  |  |  |  |  |
| 10 |  |  | IN3 | 1 (VL411) | 1.3 |  |  |  |  |  |  | 6.1 |  |  | 3.5 | 6.5 | 4.6 |  |  |  | 6.3 | 9.5 |  |  |  | 5.5 | 7.5 |  |  |  | 4.5 | 3 |  |  |  | 3.5 | 4 |
|  | EM-890K |  | CORE |  | 4 | ±0.709 | 1078x1 | 2.93 |  |  |  |  |  |  |  |  |  |  |  |  |  |  |  |  |  |  |  |  |  |  |  |  |  |  |  |  |  |
| 11 |  |  | GND4 | 1 (VL411) | 1.3 |  |  |  |  |  |  |  |  |  |  |  |  |  |  |  |  |  |  |  |  |  |  |  |  |  |  |  |  |  |  |  |  |
|  | EM-890K |  | PP |  | 8 | ±1.5 | 3313x2 | 2.97 |  |  |  |  |  |  |  |  |  |  |  |  |  |  |  |  |  |  |  |  |  |  |  |  |  |  |  |  |  |
| 12 |  |  | IN4 | 1 (VL411) | 1.3 |  |  |  |  |  |  | 6.1 |  |  | 3.5 | 6.5 | 4.6 |  |  |  | 6.3 | 9.5 |  |  |  | 5.5 | 7.5 |  |  |  | 4.5 | 3 |  |  |  | 3.5 | 4 |
|  | EM-890K |  | CORE |  | 4 | ±0.709 | 1078x1 | 2.93 |  |  |  |  |  |  |  |  |  |  |  |  |  |  |  |  |  |  |  |  |  |  |  |  |  |  |  |  |  |
| 13 |  |  | GND5 | 1 (VL411) | 1.3 |  |  |  |  |  |  |  |  |  |  |  |  |  |  |  |  |  |  |  |  |  |  |  |  |  |  |  |  |  |  |  |  |
|  | EM-890K |  | PP |  | 8 | ±1.5 | 3313x2 | 2.97 |  |  |  |  |  |  |  |  |  |  |  |  |  |  |  |  |  |  |  |  |  |  |  |  |  |  |  |  |  |
| 14 |  |  | IN5 | 1 (VL411) | 1.3 |  |  |  |  |  |  | 6.1 |  |  | 3.5 | 6.5 | 4.6 |  |  |  | 6.3 | 9.5 |  |  |  | 5.5 | 7.5 |  |  |  | 4.5 | 3 |  |  |  | 3.5 | 4 |
|  | EM-890K |  | CORE |  | 4 | ±0.709 | 1078x1 | 2.93 |  |  |  |  |  |  |  |  |  |  |  |  |  |  |  |  |  |  |  |  |  |  |  |  |  |  |  |  |  |
| 15 |  |  | GND6 | 2 (RTF) | 2.6 |  |  |  |  |  |  |  |  |  |  |  |  |  |  |  |  |  |  |  |  |  |  |  |  |  |  |  |  |  |  |  |  |
|  | EM-890K |  | PP |  | 8 | ±1.5 | 3313x2 | 2.97 |  |  |  |  |  |  |  |  |  |  |  |  |  |  |  |  |  |  |  |  |  |  |  |  |  |  |  |  |  |
| 16 |  |  | IN6 | 1 (VL411) | 1.3 |  |  |  |  |  |  | 6.1 |  |  | 3.5 | 6.5 | 4.6 |  |  |  | 6.3 | 9.5 |  |  |  | 5.5 | 7.5 |  |  |  | 4.5 | 3 |  |  |  | 3.5 | 4 |
|  | EM-890K |  | CORE |  | 4 | ±0.709 | 1078x1 | 2.93 |  |  |  |  |  |  |  |  |  |  |  |  |  |  |  |  |  |  |  |  |  |  |  |  |  |  |  |  |  |
| 17 |  |  | GND7 | 1 (VL411) | 1.3 |  |  |  |  |  |  |  |  |  |  |  |  |  |  |  |  |  |  |  |  |  |  |  |  |  |  |  |  |  |  |  |  |
|  | EM-890K |  | PP |  | 2.7 | ±0.709 | 1078x1 | 2.92 |  |  |  |  |  |  |  |  |  |  |  |  |  |  |  |  |  |  |  |  |  |  |  |  |  |  |  |  |  |
| 18 |  |  | BOTTOM | 0.5+plating | 1.95 |  |  |  |  |  |  | 5.2 |  |  | 3.5 | 5.3 | 5.5 |  |  |  | 4.9 | 9.4 |  |  |  | 4.5 | 10 |  |  |  |  |  |  |  |  | 3.5 | 4.5 |
|  |  |  | Soldermask |  | 0.6 |  |  | 3.8 |  |  |  |  |  |  |  |  |  |  |  |  |  |  |  |  |  |  |  |  |  |  |  |  |  |  |  |  |  |
|  |  |  |  | Total | 121.69999999999996 | ±10% |  |  | 0 |  |  |  |  |  |  |  |  |  |  |  |  |  |  |  |  |  |  |  |  |  |  |  |  |  |  |  |  |
